(kicad_pcb
	(version 20241229)
	(generator "pcbnew")
	(generator_version "9.0")
	(general
		(thickness 1.599998)
		(legacy_teardrops no)
	)
	(paper "A4")
	(title_block
		(title "Artix - Datacenter Secure Control Module (DC-SCM)")
		(date "2024-11-06")
		(rev "1.1.3")
		(comment 9 "footprints 388-392 of 544")
	)
	(layers
		(0 "F.Cu" signal)
		(4 "In1.Cu" signal)
		(6 "In2.Cu" signal)
		(8 "In3.Cu" signal)
		(10 "In4.Cu" signal)
		(12 "In5.Cu" signal)
		(14 "In6.Cu" signal)
		(2 "B.Cu" signal)
		(9 "F.Adhes" user "F.Adhesive")
		(11 "B.Adhes" user "B.Adhesive")
		(13 "F.Paste" user)
		(15 "B.Paste" user)
		(5 "F.SilkS" user "F.Silkscreen")
		(7 "B.SilkS" user "B.Silkscreen")
		(1 "F.Mask" user)
		(3 "B.Mask" user)
		(17 "Dwgs.User" user "User.Drawings")
		(19 "Cmts.User" user "User.Comments")
		(21 "Eco1.User" user "User.Eco1")
		(23 "Eco2.User" user "User.Eco2")
		(25 "Edge.Cuts" user)
		(27 "Margin" user)
		(31 "F.CrtYd" user "F.Courtyard")
		(29 "B.CrtYd" user "B.Courtyard")
		(35 "F.Fab" user)
		(33 "B.Fab" user)
	)
	(footprint "antmicro-footprints:C_0402_1005Metric"
		(layer "B.Cu")
		(at 107.725 95.55 180)
		(descr "Capacitor SMD 0402")
		(tags "capacitor SMD 0402")
		(property "Reference" "C199"
			(at -5.875 2.8 0)
			(layer "B.SilkS")
			(effects
				(font
					(size 0.7 0.7)
					(thickness 0.15)
				)
				(justify left bottom mirror)
			)
		)
		(property "Value" "C_4u7_0402"
			(at 0 -1.4 0)
			(layer "B.Fab")
			(effects
				(font
					(size 0.7 0.7)
					(thickness 0.15)
				)
				(justify left bottom mirror)
			)
		)
		(property "Datasheet" "https://www.murata.com/products/productdetail?partno=GRM155R61A475MEAA%23"
			(at 0 0 180)
			(layer "F.Fab")
			(hide yes)
			(effects
				(font
					(size 1.27 1.27)
					(thickness 0.15)
				)
			)
		)
		(property "Description" "SMD Multilayer Ceramic Capacitor, 4.7 µF, 10 V, 0402 [1005 Metric], ± 20%, X5R, GRM Series"
			(at 0 0 180)
			(layer "F.Fab")
			(hide yes)
			(effects
				(font
					(size 1.27 1.27)
					(thickness 0.15)
				)
			)
		)
		(property "Author" "Antmicro"
			(at 215.45 191.1 0)
			(layer "B.Fab")
			(hide yes)
			(effects
				(font
					(size 1 1)
					(thickness 0.15)
				)
				(justify mirror)
			)
		)
		(property "Dielectric" ""
			(at 215.45 191.1 0)
			(layer "B.Fab")
			(hide yes)
			(effects
				(font
					(size 1 1)
					(thickness 0.15)
				)
				(justify mirror)
			)
		)
		(property "License" "Apache-2.0"
			(at 215.45 191.1 0)
			(layer "B.Fab")
			(hide yes)
			(effects
				(font
					(size 1 1)
					(thickness 0.15)
				)
				(justify mirror)
			)
		)
		(property "MPN" "GRM155R61A475MEAAD"
			(at 215.45 191.1 0)
			(layer "B.Fab")
			(hide yes)
			(effects
				(font
					(size 1 1)
					(thickness 0.15)
				)
				(justify mirror)
			)
		)
		(property "Manufacturer" "Murata"
			(at 215.45 191.1 0)
			(layer "B.Fab")
			(hide yes)
			(effects
				(font
					(size 1 1)
					(thickness 0.15)
				)
				(justify mirror)
			)
		)
		(property "Val" "4u7"
			(at 215.45 191.1 0)
			(layer "B.Fab")
			(hide yes)
			(effects
				(font
					(size 1 1)
					(thickness 0.15)
				)
				(justify mirror)
			)
		)
		(property "Voltage" ""
			(at 215.45 191.1 0)
			(layer "B.Fab")
			(hide yes)
			(effects
				(font
					(size 1 1)
					(thickness 0.15)
				)
				(justify mirror)
			)
		)
		(sheetname "/Ethernet/")
		(sheetfile "ethernet.kicad_sch")
		(attr smd)
		(fp_rect
			(start -0.925 0.47)
			(end 0.925 -0.47)
			(stroke
				(width 0.05)
				(type default)
			)
			(fill no)
			(layer "B.CrtYd")
		)
		(fp_line
			(start 0.504 0.25)
			(end 0.504 -0.248)
			(stroke
				(width 0.15)
				(type solid)
			)
			(layer "B.Fab")
		)
		(fp_line
			(start 0.504 -0.248)
			(end -0.494 -0.248)
			(stroke
				(width 0.15)
				(type solid)
			)
			(layer "B.Fab")
		)
		(fp_line
			(start -0.494 0.25)
			(end 0.504 0.25)
			(stroke
				(width 0.15)
				(type solid)
			)
			(layer "B.Fab")
		)
		(fp_line
			(start -0.494 -0.248)
			(end -0.494 0.25)
			(stroke
				(width 0.15)
				(type solid)
			)
			(layer "B.Fab")
		)
		(pad "1" smd roundrect
			(at -0.48 0 180)
			(size 0.59 0.64)
			(layers "B.Cu" "B.Mask" "B.Paste")
			(roundrect_rratio 0.25)
			(net 1 "GND")
			(pintype "passive")
		)
		(pad "2" smd roundrect
			(at 0.48 0 180)
			(size 0.59 0.64)
			(layers "B.Cu" "B.Mask" "B.Paste")
			(roundrect_rratio 0.25)
			(net 404 "/Ethernet/AVDDL_PLL")
			(pintype "passive")
		)
	)
	(footprint "antmicro-footprints:C_0402_1005Metric"
		(layer "B.Cu")
		(at 107.725 94.6 180)
		(descr "Capacitor SMD 0402")
		(tags "capacitor SMD 0402")
		(property "Reference" "C203"
			(at -5.875 2.8 0)
			(layer "B.SilkS")
			(effects
				(font
					(size 0.7 0.7)
					(thickness 0.15)
				)
				(justify left bottom mirror)
			)
		)
		(property "Value" "C_100n_0402"
			(at 0 -1.4 0)
			(layer "B.Fab")
			(effects
				(font
					(size 0.7 0.7)
					(thickness 0.15)
				)
				(justify left bottom mirror)
			)
		)
		(property "Datasheet" "https://www.murata.com/products/productdetail?partno=GRM155R61H104KE14%23"
			(at 0 0 180)
			(layer "F.Fab")
			(hide yes)
			(effects
				(font
					(size 1.27 1.27)
					(thickness 0.15)
				)
			)
		)
		(property "Description" "SMD Multilayer Ceramic Capacitor, 0.1 µF, 50 V, 0402 [1005 Metric], ± 10%, X5R, GRM Series"
			(at 0 0 180)
			(layer "F.Fab")
			(hide yes)
			(effects
				(font
					(size 1.27 1.27)
					(thickness 0.15)
				)
			)
		)
		(property "Author" "Antmicro"
			(at 215.45 189.2 0)
			(layer "B.Fab")
			(hide yes)
			(effects
				(font
					(size 1 1)
					(thickness 0.15)
				)
				(justify mirror)
			)
		)
		(property "Dielectric" "X5R"
			(at 215.45 189.2 0)
			(layer "B.Fab")
			(hide yes)
			(effects
				(font
					(size 1 1)
					(thickness 0.15)
				)
				(justify mirror)
			)
		)
		(property "License" "Apache-2.0"
			(at 215.45 189.2 0)
			(layer "B.Fab")
			(hide yes)
			(effects
				(font
					(size 1 1)
					(thickness 0.15)
				)
				(justify mirror)
			)
		)
		(property "MPN" "GRM155R61H104KE14D"
			(at 215.45 189.2 0)
			(layer "B.Fab")
			(hide yes)
			(effects
				(font
					(size 1 1)
					(thickness 0.15)
				)
				(justify mirror)
			)
		)
		(property "Manufacturer" "Murata"
			(at 215.45 189.2 0)
			(layer "B.Fab")
			(hide yes)
			(effects
				(font
					(size 1 1)
					(thickness 0.15)
				)
				(justify mirror)
			)
		)
		(property "Val" "100n"
			(at 215.45 189.2 0)
			(layer "B.Fab")
			(hide yes)
			(effects
				(font
					(size 1 1)
					(thickness 0.15)
				)
				(justify mirror)
			)
		)
		(property "Voltage" "50V"
			(at 215.45 189.2 0)
			(layer "B.Fab")
			(hide yes)
			(effects
				(font
					(size 1 1)
					(thickness 0.15)
				)
				(justify mirror)
			)
		)
		(sheetname "/Ethernet/")
		(sheetfile "ethernet.kicad_sch")
		(attr smd)
		(fp_rect
			(start -0.925 0.47)
			(end 0.925 -0.47)
			(stroke
				(width 0.05)
				(type default)
			)
			(fill no)
			(layer "B.CrtYd")
		)
		(fp_line
			(start 0.504 0.25)
			(end 0.504 -0.248)
			(stroke
				(width 0.15)
				(type solid)
			)
			(layer "B.Fab")
		)
		(fp_line
			(start 0.504 -0.248)
			(end -0.494 -0.248)
			(stroke
				(width 0.15)
				(type solid)
			)
			(layer "B.Fab")
		)
		(fp_line
			(start -0.494 0.25)
			(end 0.504 0.25)
			(stroke
				(width 0.15)
				(type solid)
			)
			(layer "B.Fab")
		)
		(fp_line
			(start -0.494 -0.248)
			(end -0.494 0.25)
			(stroke
				(width 0.15)
				(type solid)
			)
			(layer "B.Fab")
		)
		(pad "1" smd roundrect
			(at -0.48 0 180)
			(size 0.59 0.64)
			(layers "B.Cu" "B.Mask" "B.Paste")
			(roundrect_rratio 0.25)
			(net 1 "GND")
			(pintype "passive")
		)
		(pad "2" smd roundrect
			(at 0.48 0 180)
			(size 0.59 0.64)
			(layers "B.Cu" "B.Mask" "B.Paste")
			(roundrect_rratio 0.25)
			(net 404 "/Ethernet/AVDDL_PLL")
			(pintype "passive")
		)
	)
	(footprint "antmicro-footprints:C_0402_1005Metric"
		(layer "B.Cu")
		(at 107.725 97.45 180)
		(descr "Capacitor SMD 0402")
		(tags "capacitor SMD 0402")
		(property "Reference" "C207"
			(at -5.875 2.8 0)
			(layer "B.SilkS")
			(effects
				(font
					(size 0.7 0.7)
					(thickness 0.15)
				)
				(justify left bottom mirror)
			)
		)
		(property "Value" "C_10n_0402"
			(at 0 -1.4 0)
			(layer "B.Fab")
			(effects
				(font
					(size 0.7 0.7)
					(thickness 0.15)
				)
				(justify left bottom mirror)
			)
		)
		(property "Datasheet" "https://www.murata.com/products/productdetail?partno=GRM155R71H103KA88%23"
			(at 0 0 180)
			(layer "F.Fab")
			(hide yes)
			(effects
				(font
					(size 1.27 1.27)
					(thickness 0.15)
				)
			)
		)
		(property "Description" "SMD Multilayer Ceramic Capacitor, 10000 pF, 50 V, 0402 [1005 Metric], ± 10%, X7R, GRM Series"
			(at 0 0 180)
			(layer "F.Fab")
			(hide yes)
			(effects
				(font
					(size 1.27 1.27)
					(thickness 0.15)
				)
			)
		)
		(property "Author" "Antmicro"
			(at 215.45 194.9 0)
			(layer "B.Fab")
			(hide yes)
			(effects
				(font
					(size 1 1)
					(thickness 0.15)
				)
				(justify mirror)
			)
		)
		(property "Dielectric" "X7R"
			(at 215.45 194.9 0)
			(layer "B.Fab")
			(hide yes)
			(effects
				(font
					(size 1 1)
					(thickness 0.15)
				)
				(justify mirror)
			)
		)
		(property "License" "Apache-2.0"
			(at 215.45 194.9 0)
			(layer "B.Fab")
			(hide yes)
			(effects
				(font
					(size 1 1)
					(thickness 0.15)
				)
				(justify mirror)
			)
		)
		(property "MPN" "GRM155R71H103KA88D"
			(at 215.45 194.9 0)
			(layer "B.Fab")
			(hide yes)
			(effects
				(font
					(size 1 1)
					(thickness 0.15)
				)
				(justify mirror)
			)
		)
		(property "Manufacturer" "Murata"
			(at 215.45 194.9 0)
			(layer "B.Fab")
			(hide yes)
			(effects
				(font
					(size 1 1)
					(thickness 0.15)
				)
				(justify mirror)
			)
		)
		(property "Val" "10n"
			(at 215.45 194.9 0)
			(layer "B.Fab")
			(hide yes)
			(effects
				(font
					(size 1 1)
					(thickness 0.15)
				)
				(justify mirror)
			)
		)
		(property "Voltage" "50V"
			(at 215.45 194.9 0)
			(layer "B.Fab")
			(hide yes)
			(effects
				(font
					(size 1 1)
					(thickness 0.15)
				)
				(justify mirror)
			)
		)
		(sheetname "/Ethernet/")
		(sheetfile "ethernet.kicad_sch")
		(attr smd)
		(fp_rect
			(start -0.925 0.47)
			(end 0.925 -0.47)
			(stroke
				(width 0.05)
				(type default)
			)
			(fill no)
			(layer "B.CrtYd")
		)
		(fp_line
			(start 0.504 0.25)
			(end 0.504 -0.248)
			(stroke
				(width 0.15)
				(type solid)
			)
			(layer "B.Fab")
		)
		(fp_line
			(start 0.504 -0.248)
			(end -0.494 -0.248)
			(stroke
				(width 0.15)
				(type solid)
			)
			(layer "B.Fab")
		)
		(fp_line
			(start -0.494 0.25)
			(end 0.504 0.25)
			(stroke
				(width 0.15)
				(type solid)
			)
			(layer "B.Fab")
		)
		(fp_line
			(start -0.494 -0.248)
			(end -0.494 0.25)
			(stroke
				(width 0.15)
				(type solid)
			)
			(layer "B.Fab")
		)
		(pad "1" smd roundrect
			(at -0.48 0 180)
			(size 0.59 0.64)
			(layers "B.Cu" "B.Mask" "B.Paste")
			(roundrect_rratio 0.25)
			(net 1 "GND")
			(pintype "passive")
		)
		(pad "2" smd roundrect
			(at 0.48 0 180)
			(size 0.59 0.64)
			(layers "B.Cu" "B.Mask" "B.Paste")
			(roundrect_rratio 0.25)
			(net 2 "VCC3V3")
			(pintype "passive")
		)
	)
	(footprint "antmicro-footprints:C_0402_1005Metric"
		(layer "B.Cu")
		(at 107.725 96.5 180)
		(descr "Capacitor SMD 0402")
		(tags "capacitor SMD 0402")
		(property "Reference" "C208"
			(at -5.875 2.8 0)
			(layer "B.SilkS")
			(effects
				(font
					(size 0.7 0.7)
					(thickness 0.15)
				)
				(justify left bottom mirror)
			)
		)
		(property "Value" "C_10n_0402"
			(at 0 -1.4 0)
			(layer "B.Fab")
			(effects
				(font
					(size 0.7 0.7)
					(thickness 0.15)
				)
				(justify left bottom mirror)
			)
		)
		(property "Datasheet" "https://www.murata.com/products/productdetail?partno=GRM155R71H103KA88%23"
			(at 0 0 180)
			(layer "F.Fab")
			(hide yes)
			(effects
				(font
					(size 1.27 1.27)
					(thickness 0.15)
				)
			)
		)
		(property "Description" "SMD Multilayer Ceramic Capacitor, 10000 pF, 50 V, 0402 [1005 Metric], ± 10%, X7R, GRM Series"
			(at 0 0 180)
			(layer "F.Fab")
			(hide yes)
			(effects
				(font
					(size 1.27 1.27)
					(thickness 0.15)
				)
			)
		)
		(property "Author" "Antmicro"
			(at 215.45 193 0)
			(layer "B.Fab")
			(hide yes)
			(effects
				(font
					(size 1 1)
					(thickness 0.15)
				)
				(justify mirror)
			)
		)
		(property "Dielectric" "X7R"
			(at 215.45 193 0)
			(layer "B.Fab")
			(hide yes)
			(effects
				(font
					(size 1 1)
					(thickness 0.15)
				)
				(justify mirror)
			)
		)
		(property "License" "Apache-2.0"
			(at 215.45 193 0)
			(layer "B.Fab")
			(hide yes)
			(effects
				(font
					(size 1 1)
					(thickness 0.15)
				)
				(justify mirror)
			)
		)
		(property "MPN" "GRM155R71H103KA88D"
			(at 215.45 193 0)
			(layer "B.Fab")
			(hide yes)
			(effects
				(font
					(size 1 1)
					(thickness 0.15)
				)
				(justify mirror)
			)
		)
		(property "Manufacturer" "Murata"
			(at 215.45 193 0)
			(layer "B.Fab")
			(hide yes)
			(effects
				(font
					(size 1 1)
					(thickness 0.15)
				)
				(justify mirror)
			)
		)
		(property "Val" "10n"
			(at 215.45 193 0)
			(layer "B.Fab")
			(hide yes)
			(effects
				(font
					(size 1 1)
					(thickness 0.15)
				)
				(justify mirror)
			)
		)
		(property "Voltage" "50V"
			(at 215.45 193 0)
			(layer "B.Fab")
			(hide yes)
			(effects
				(font
					(size 1 1)
					(thickness 0.15)
				)
				(justify mirror)
			)
		)
		(sheetname "/Ethernet/")
		(sheetfile "ethernet.kicad_sch")
		(attr smd)
		(fp_rect
			(start -0.925 0.47)
			(end 0.925 -0.47)
			(stroke
				(width 0.05)
				(type default)
			)
			(fill no)
			(layer "B.CrtYd")
		)
		(fp_line
			(start 0.504 0.25)
			(end 0.504 -0.248)
			(stroke
				(width 0.15)
				(type solid)
			)
			(layer "B.Fab")
		)
		(fp_line
			(start 0.504 -0.248)
			(end -0.494 -0.248)
			(stroke
				(width 0.15)
				(type solid)
			)
			(layer "B.Fab")
		)
		(fp_line
			(start -0.494 0.25)
			(end 0.504 0.25)
			(stroke
				(width 0.15)
				(type solid)
			)
			(layer "B.Fab")
		)
		(fp_line
			(start -0.494 -0.248)
			(end -0.494 0.25)
			(stroke
				(width 0.15)
				(type solid)
			)
			(layer "B.Fab")
		)
		(pad "1" smd roundrect
			(at -0.48 0 180)
			(size 0.59 0.64)
			(layers "B.Cu" "B.Mask" "B.Paste")
			(roundrect_rratio 0.25)
			(net 1 "GND")
			(pintype "passive")
		)
		(pad "2" smd roundrect
			(at 0.48 0 180)
			(size 0.59 0.64)
			(layers "B.Cu" "B.Mask" "B.Paste")
			(roundrect_rratio 0.25)
			(net 404 "/Ethernet/AVDDL_PLL")
			(pintype "passive")
		)
	)
	(footprint "antmicro-footprints:C_0402_1005Metric"
		(layer "B.Cu")
		(at 107.725 98.4 180)
		(descr "Capacitor SMD 0402")
		(tags "capacitor SMD 0402")
		(property "Reference" "C214"
			(at -5.875 2.8 0)
			(layer "B.SilkS")
			(effects
				(font
					(size 0.7 0.7)
					(thickness 0.15)
				)
				(justify left bottom mirror)
			)
		)
		(property "Value" "C_10n_0402"
			(at 0 -1.4 0)
			(layer "B.Fab")
			(effects
				(font
					(size 0.7 0.7)
					(thickness 0.15)
				)
				(justify left bottom mirror)
			)
		)
		(property "Datasheet" "https://www.murata.com/products/productdetail?partno=GRM155R71H103KA88%23"
			(at 0 0 180)
			(layer "F.Fab")
			(hide yes)
			(effects
				(font
					(size 1.27 1.27)
					(thickness 0.15)
				)
			)
		)
		(property "Description" "SMD Multilayer Ceramic Capacitor, 10000 pF, 50 V, 0402 [1005 Metric], ± 10%, X7R, GRM Series"
			(at 0 0 180)
			(layer "F.Fab")
			(hide yes)
			(effects
				(font
					(size 1.27 1.27)
					(thickness 0.15)
				)
			)
		)
		(property "Author" "Antmicro"
			(at 215.45 196.8 0)
			(layer "B.Fab")
			(hide yes)
			(effects
				(font
					(size 1 1)
					(thickness 0.15)
				)
				(justify mirror)
			)
		)
		(property "Dielectric" "X7R"
			(at 215.45 196.8 0)
			(layer "B.Fab")
			(hide yes)
			(effects
				(font
					(size 1 1)
					(thickness 0.15)
				)
				(justify mirror)
			)
		)
		(property "License" "Apache-2.0"
			(at 215.45 196.8 0)
			(layer "B.Fab")
			(hide yes)
			(effects
				(font
					(size 1 1)
					(thickness 0.15)
				)
				(justify mirror)
			)
		)
		(property "MPN" "GRM155R71H103KA88D"
			(at 215.45 196.8 0)
			(layer "B.Fab")
			(hide yes)
			(effects
				(font
					(size 1 1)
					(thickness 0.15)
				)
				(justify mirror)
			)
		)
		(property "Manufacturer" "Murata"
			(at 215.45 196.8 0)
			(layer "B.Fab")
			(hide yes)
			(effects
				(font
					(size 1 1)
					(thickness 0.15)
				)
				(justify mirror)
			)
		)
		(property "Val" "10n"
			(at 215.45 196.8 0)
			(layer "B.Fab")
			(hide yes)
			(effects
				(font
					(size 1 1)
					(thickness 0.15)
				)
				(justify mirror)
			)
		)
		(property "Voltage" "50V"
			(at 215.45 196.8 0)
			(layer "B.Fab")
			(hide yes)
			(effects
				(font
					(size 1 1)
					(thickness 0.15)
				)
				(justify mirror)
			)
		)
		(sheetname "/Ethernet/")
		(sheetfile "ethernet.kicad_sch")
		(attr smd)
		(fp_rect
			(start -0.925 0.47)
			(end 0.925 -0.47)
			(stroke
				(width 0.05)
				(type default)
			)
			(fill no)
			(layer "B.CrtYd")
		)
		(fp_line
			(start 0.504 0.25)
			(end 0.504 -0.248)
			(stroke
				(width 0.15)
				(type solid)
			)
			(layer "B.Fab")
		)
		(fp_line
			(start 0.504 -0.248)
			(end -0.494 -0.248)
			(stroke
				(width 0.15)
				(type solid)
			)
			(layer "B.Fab")
		)
		(fp_line
			(start -0.494 0.25)
			(end 0.504 0.25)
			(stroke
				(width 0.15)
				(type solid)
			)
			(layer "B.Fab")
		)
		(fp_line
			(start -0.494 -0.248)
			(end -0.494 0.25)
			(stroke
				(width 0.15)
				(type solid)
			)
			(layer "B.Fab")
		)
		(pad "1" smd roundrect
			(at -0.48 0 180)
			(size 0.59 0.64)
			(layers "B.Cu" "B.Mask" "B.Paste")
			(roundrect_rratio 0.25)
			(net 1 "GND")
			(pintype "passive")
		)
		(pad "2" smd roundrect
			(at 0.48 0 180)
			(size 0.59 0.64)
			(layers "B.Cu" "B.Mask" "B.Paste")
			(roundrect_rratio 0.25)
			(net 339 "VCC1V2")
			(pintype "passive")
		)
	)
)
